(kicad_pcb
	(version 20260206)
	(generator "pcbnew")
	(generator_version "10.0")
	(general
		(thickness 1.6)
		(legacy_teardrops no)
	)
	(paper "A4")
	(title_block
		(title "Bryce Canyon_R.DPB_16317-1_OCP.brd")
		(comment 1 "Bryce Canyon / footprints 368-374 of 2099")
	)
	(layers
		(0 "F.Cu" signal "TOP")
		(4 "In1.Cu" signal "L2GND")
		(6 "In2.Cu" signal "L3")
		(8 "In3.Cu" signal "L4VCC")
		(10 "In4.Cu" signal "L5VCC")
		(12 "In5.Cu" signal "L6")
		(14 "In6.Cu" signal "L7GND")
		(2 "B.Cu" signal "BOTTOM")
		(9 "F.Adhes" user "F.Adhesive")
		(11 "B.Adhes" user "B.Adhesive")
		(13 "F.Paste" user "Package Geometry/Pastemask Top")
		(15 "B.Paste" user "Package Geometry/Pastemask Bottom")
		(5 "F.SilkS" user "Ref Des/Silkscreen Top")
		(7 "B.SilkS" user "Ref Des/Silkscreen Bottom")
		(1 "F.Mask" user "Board Geometry/Soldermask Top")
		(3 "B.Mask" user "Board Geometry/Soldermask Bottom")
		(17 "Dwgs.User" user "User.Drawings")
		(19 "Cmts.User" user "User.Comments")
		(21 "Eco1.User" user "User.Eco1")
		(23 "Eco2.User" user "User.Eco2")
		(25 "Edge.Cuts" user "Board Geometry/Outline")
		(27 "Margin" user)
		(31 "F.CrtYd" user "Package Geometry/Place Bound Top")
		(29 "B.CrtYd" user "Package Geometry/Place Bound Bottom")
		(35 "F.Fab" user "Ref Des/Assembly Top")
		(33 "B.Fab" user "Ref Des/Assembly Bottom")
	)
	(footprint ""
		(layer "F.Cu")
		(at 423.577004 -364.236 -90)
		(property "Reference" "R961"
			(at 0 0 270)
			(layer "F.SilkS")
			(hide yes)
			(effects
				(font
					(size 1.27 1.27)
				)
			)
		)
		(property "Value" "10KR2F-2-GP"
			(at 0.064008 -3.993896 270)
			(unlocked yes)
			(layer "F.Fab")
			(hide yes)
			(effects
				(font
					(size 1.016 1.016)
					(thickness 0.1524)
				)
			)
		)
		(property "Device Type" "R402H16"
			(at 0.064008 -5.517896 270)
			(unlocked yes)
			(layer "F.Fab")
			(hide yes)
			(effects
				(font
					(size 1.016 1.016)
					(thickness 0.1524)
				)
			)
		)
		(duplicate_pad_numbers_are_jumpers no)
		(fp_line
			(start -0.508 -0.9398)
			(end -0.508 0.9398)
			(stroke
				(width 0.1524)
				(type default)
			)
			(layer "F.SilkS")
		)
		(fp_line
			(start 0.508 -0.9398)
			(end -0.508 -0.9398)
			(stroke
				(width 0.1524)
				(type default)
			)
			(layer "F.SilkS")
		)
		(fp_rect
			(start -0.508 0.9398)
			(end 0.508 -0.9398)
			(stroke
				(width 0)
				(type default)
			)
			(fill no)
			(layer "F.CrtYd")
		)
		(fp_rect
			(start -0.508 0.9398)
			(end 0.508 -0.9398)
			(stroke
				(width 0)
				(type default)
			)
			(fill no)
			(layer "F.Fab")
		)
		(pad "1" smd custom
			(at 0 -0.4445 270)
			(size 0.1397 0.1397)
			(layers "F.Cu" "F.Mask" "F.Paste")
			(net "GND")
			(options
				(clearance outline)
				(anchor circle)
			)
			(primitives
				(gr_poly
					(pts
						(arc
							(start -0.1778 -0.2794)
							(mid -0.249642 -0.249642)
							(end -0.2794 -0.1778)
						)
						(arc
							(start -0.2794 0.1778)
							(mid -0.249642 0.249642)
							(end -0.1778 0.2794)
						)
						(arc
							(start 0.1778 0.2794)
							(mid 0.249642 0.249642)
							(end 0.2794 0.1778)
						)
						(arc
							(start 0.2794 -0.1778)
							(mid 0.249642 -0.249642)
							(end 0.1778 -0.2794)
						)
					)
					(width 0)
					(fill yes)
				)
			)
		)
		(pad "2" smd custom
			(at 0 0.4445 270)
			(size 0.1397 0.1397)
			(layers "F.Cu" "F.Mask" "F.Paste")
			(net "FANTACH_F3")
			(options
				(clearance outline)
				(anchor circle)
			)
			(primitives
				(gr_poly
					(pts
						(arc
							(start -0.1778 -0.2794)
							(mid -0.249642 -0.249642)
							(end -0.2794 -0.1778)
						)
						(arc
							(start -0.2794 0.1778)
							(mid -0.249642 0.249642)
							(end -0.1778 0.2794)
						)
						(arc
							(start 0.1778 0.2794)
							(mid 0.249642 0.249642)
							(end 0.2794 0.1778)
						)
						(arc
							(start 0.2794 -0.1778)
							(mid 0.249642 -0.249642)
							(end 0.1778 -0.2794)
						)
					)
					(width 0)
					(fill yes)
				)
			)
		)
	)
	(footprint ""
		(layer "F.Cu")
		(at 320.287396 -379.3236 -90)
		(property "Reference" "Q206"
			(at 0 0 270)
			(layer "F.SilkS")
			(hide yes)
			(effects
				(font
					(size 1.27 1.27)
				)
			)
		)
		(property "Value" "SSM6P39TU-GP"
			(at 0.0508 -11.5824 270)
			(unlocked yes)
			(layer "F.Fab")
			(hide yes)
			(effects
				(font
					(size 1.016 1.016)
					(thickness 0.1524)
				)
			)
		)
		(property "Device Type" "UMT6H30"
			(at 0.0508 -13.1572 270)
			(unlocked yes)
			(layer "F.Fab")
			(hide yes)
			(effects
				(font
					(size 1.016 1.016)
					(thickness 0.1524)
				)
			)
		)
		(duplicate_pad_numbers_are_jumpers no)
		(fp_line
			(start 1.524 0.36449)
			(end -1.27 0.36449)
			(stroke
				(width 0.1524)
				(type default)
			)
			(layer "F.SilkS")
		)
		(fp_line
			(start 1.09347 0)
			(end 1.45796 0.36449)
			(stroke
				(width 0.1524)
				(type default)
			)
			(layer "F.SilkS")
		)
		(fp_line
			(start -1.27 -0.36449)
			(end -1.27 0.36449)
			(stroke
				(width 0.1524)
				(type default)
			)
			(layer "F.SilkS")
		)
		(fp_line
			(start -1.27 -0.36449)
			(end 1.524 -0.36449)
			(stroke
				(width 0.1524)
				(type default)
			)
			(layer "F.SilkS")
		)
		(fp_line
			(start 1.45796 -0.36449)
			(end 1.09347 0)
			(stroke
				(width 0.1524)
				(type default)
			)
			(layer "F.SilkS")
		)
		(fp_line
			(start 1.524 -0.36449)
			(end 1.524 0.36449)
			(stroke
				(width 0.1524)
				(type default)
			)
			(layer "F.SilkS")
		)
		(fp_line
			(start 1.524 -0.36449)
			(end 1.45796 -0.36449)
			(stroke
				(width 0.1524)
				(type default)
			)
			(layer "F.SilkS")
		)
		(fp_line
			(start 1.524 -0.36449)
			(end 1.524 -1.82245)
			(stroke
				(width 0.508)
				(type default)
			)
			(layer "F.SilkS")
		)
		(fp_poly
			(pts
				(xy -0.65024 0.36449) (xy -0.65024 -0.36449) (xy 0.65024 -0.36449) (xy 0.65024 0.36449)
			)
			(stroke
				(width 0)
				(type default)
			)
			(fill yes)
			(layer "F.SilkS")
		)
		(fp_poly
			(pts
				(xy 1.016 -1.0668) (xy 1.016 1.0668) (xy -1.016 1.0668) (xy -1.016 -1.0668)
			)
			(stroke
				(width 0)
				(type default)
			)
			(fill no)
			(layer "F.CrtYd")
		)
		(fp_poly
			(pts
				(xy -1.524 1.905) (xy 1.524 1.905) (xy 1.524 -1.06426) (xy 1.016 -1.06426) (xy 1.016 1.0668) (xy -1.016 1.0668)
				(xy -1.016 -1.0668) (xy 1.524 -1.0668) (xy 1.524 -1.905) (xy -1.524 -1.905)
			)
			(stroke
				(width 0)
				(type default)
			)
			(fill no)
			(layer "F.CrtYd")
		)
		(fp_poly
			(pts
				(xy -1.524 -1.905) (xy -1.524 1.905) (xy 1.524 1.905) (xy 1.524 -1.905)
			)
			(stroke
				(width 0)
				(type default)
			)
			(fill no)
			(layer "F.Fab")
		)
		(pad "1" smd rect
			(at 0.65024 -1.02489 270)
			(size 0.4064 0.8128)
			(layers "F.Cu" "F.Mask" "F.Paste")
			(net "P12V_IN")
		)
		(pad "2" smd rect
			(at 0 -1.02489 270)
			(size 0.4064 0.8128)
			(layers "F.Cu" "F.Mask" "F.Paste")
			(net "FAN_YELLOW_LED2")
		)
		(pad "3" smd rect
			(at -0.65024 -1.02489 270)
			(size 0.4064 0.8128)
			(layers "F.Cu" "F.Mask" "F.Paste")
			(net "FAN_BLUE2")
		)
		(pad "4" smd rect
			(at -0.65024 1.02489 270)
			(size 0.4064 0.8128)
			(layers "F.Cu" "F.Mask" "F.Paste")
			(net "P12V_IN")
		)
		(pad "5" smd rect
			(at 0 1.02489 270)
			(size 0.4064 0.8128)
			(layers "F.Cu" "F.Mask" "F.Paste")
			(net "FAN_BLUE_LED2")
		)
		(pad "6" smd rect
			(at 0.65024 1.02489 270)
			(size 0.4064 0.8128)
			(layers "F.Cu" "F.Mask" "F.Paste")
			(net "FAN_YELLOW_2")
		)
	)
	(footprint ""
		(layer "F.Cu")
		(at 336.296 -360.2355 180)
		(property "Reference" "C391"
			(at 0 0 180)
			(layer "F.SilkS")
			(hide yes)
			(effects
				(font
					(size 1.27 1.27)
				)
			)
		)
		(property "Value" "SCD033U25V2KX-GP"
			(at 1.1811 -2.7051 180)
			(unlocked yes)
			(layer "F.Fab")
			(hide yes)
			(effects
				(font
					(size 1.016 1.016)
					(thickness 0.1524)
				)
			)
		)
		(property "Device Type" "C402H22"
			(at 1.1811 -4.2291 180)
			(unlocked yes)
			(layer "F.Fab")
			(hide yes)
			(effects
				(font
					(size 1.016 1.016)
					(thickness 0.1524)
				)
			)
		)
		(duplicate_pad_numbers_are_jumpers no)
		(fp_rect
			(start -0.4318 0.9525)
			(end 0.4318 -0.9525)
			(stroke
				(width 0)
				(type default)
			)
			(fill no)
			(layer "F.CrtYd")
		)
		(fp_rect
			(start -0.4318 0.9525)
			(end 0.4318 -0.9525)
			(stroke
				(width 0)
				(type default)
			)
			(fill no)
			(layer "F.Fab")
		)
		(pad "1" smd custom
			(at 0 -0.4445 180)
			(size 0.1524 0.1524)
			(layers "F.Cu" "F.Mask" "F.Paste")
			(net "GATE_FAN2_R")
			(options
				(clearance outline)
				(anchor circle)
			)
			(primitives
				(gr_poly
					(pts
						(arc
							(start 0.3048 -0.2032)
							(mid 0.275042 -0.275042)
							(end 0.2032 -0.3048)
						)
						(arc
							(start -0.2032 -0.3048)
							(mid -0.275042 -0.275042)
							(end -0.3048 -0.2032)
						)
						(arc
							(start -0.3048 0.2032)
							(mid -0.275042 0.275042)
							(end -0.2032 0.3048)
						)
						(arc
							(start 0.2032 0.3048)
							(mid 0.275042 0.275042)
							(end 0.3048 0.2032)
						)
					)
					(width 0)
					(fill yes)
				)
			)
		)
		(pad "2" smd custom
			(at 0 0.4445 180)
			(size 0.1524 0.1524)
			(layers "F.Cu" "F.Mask" "F.Paste")
			(net "P12V_IN")
			(options
				(clearance outline)
				(anchor circle)
			)
			(primitives
				(gr_poly
					(pts
						(arc
							(start 0.3048 -0.2032)
							(mid 0.275042 -0.275042)
							(end 0.2032 -0.3048)
						)
						(arc
							(start -0.2032 -0.3048)
							(mid -0.275042 -0.275042)
							(end -0.3048 -0.2032)
						)
						(arc
							(start -0.3048 0.2032)
							(mid -0.275042 0.275042)
							(end -0.2032 0.3048)
						)
						(arc
							(start 0.2032 0.3048)
							(mid 0.275042 0.275042)
							(end 0.3048 0.2032)
						)
					)
					(width 0)
					(fill yes)
				)
			)
		)
	)
	(footprint ""
		(layer "F.Cu")
		(at 63.7286 -31.6484)
		(property "Reference" "C362"
			(at 0 0 0)
			(layer "F.SilkS")
			(hide yes)
			(effects
				(font
					(size 1.27 1.27)
				)
			)
		)
		(property "Value" "SCD01U50V2KX-1GP"
			(at 1.1811 -2.7051 0)
			(unlocked yes)
			(layer "F.Fab")
			(hide yes)
			(effects
				(font
					(size 1.016 1.016)
					(thickness 0.1524)
				)
			)
		)
		(property "Device Type" "C402H22"
			(at 1.1811 -4.2291 0)
			(unlocked yes)
			(layer "F.Fab")
			(hide yes)
			(effects
				(font
					(size 1.016 1.016)
					(thickness 0.1524)
				)
			)
		)
		(duplicate_pad_numbers_are_jumpers no)
		(fp_rect
			(start -0.4318 0.9525)
			(end 0.4318 -0.9525)
			(stroke
				(width 0)
				(type default)
			)
			(fill no)
			(layer "F.CrtYd")
		)
		(fp_rect
			(start -0.4318 0.9525)
			(end 0.4318 -0.9525)
			(stroke
				(width 0)
				(type default)
			)
			(fill no)
			(layer "F.Fab")
		)
		(pad "1" smd custom
			(at 0 -0.4445)
			(size 0.1524 0.1524)
			(layers "F.Cu" "F.Mask" "F.Paste")
			(net "HDD_PRSNT_25")
			(options
				(clearance outline)
				(anchor circle)
			)
			(primitives
				(gr_poly
					(pts
						(arc
							(start 0.3048 -0.2032)
							(mid 0.275042 -0.275042)
							(end 0.2032 -0.3048)
						)
						(arc
							(start -0.2032 -0.3048)
							(mid -0.275042 -0.275042)
							(end -0.3048 -0.2032)
						)
						(arc
							(start -0.3048 0.2032)
							(mid -0.275042 0.275042)
							(end -0.2032 0.3048)
						)
						(arc
							(start 0.2032 0.3048)
							(mid 0.275042 0.275042)
							(end 0.3048 0.2032)
						)
					)
					(width 0)
					(fill yes)
				)
			)
		)
		(pad "2" smd custom
			(at 0 0.4445)
			(size 0.1524 0.1524)
			(layers "F.Cu" "F.Mask" "F.Paste")
			(net "GND")
			(options
				(clearance outline)
				(anchor circle)
			)
			(primitives
				(gr_poly
					(pts
						(arc
							(start 0.3048 -0.2032)
							(mid 0.275042 -0.275042)
							(end 0.2032 -0.3048)
						)
						(arc
							(start -0.2032 -0.3048)
							(mid -0.275042 -0.275042)
							(end -0.3048 -0.2032)
						)
						(arc
							(start -0.3048 0.2032)
							(mid -0.275042 0.275042)
							(end -0.2032 0.3048)
						)
						(arc
							(start 0.2032 0.3048)
							(mid 0.275042 0.275042)
							(end 0.3048 0.2032)
						)
					)
					(width 0)
					(fill yes)
				)
			)
		)
	)
	(footprint ""
		(layer "F.Cu")
		(at 471.805 -253.111 90)
		(property "Reference" "R339"
			(at 0 0 90)
			(layer "F.SilkS")
			(hide yes)
			(effects
				(font
					(size 1.27 1.27)
				)
			)
		)
		(property "Value" "4K7R2J-2-GP"
			(at 0.064008 -3.993896 90)
			(unlocked yes)
			(layer "F.Fab")
			(hide yes)
			(effects
				(font
					(size 1.016 1.016)
					(thickness 0.1524)
				)
			)
		)
		(property "Device Type" "R402H16"
			(at 0.064008 -5.517896 90)
			(unlocked yes)
			(layer "F.Fab")
			(hide yes)
			(effects
				(font
					(size 1.016 1.016)
					(thickness 0.1524)
				)
			)
		)
		(duplicate_pad_numbers_are_jumpers no)
		(fp_line
			(start 0.508 -0.9398)
			(end -0.508 -0.9398)
			(stroke
				(width 0.1524)
				(type default)
			)
			(layer "F.SilkS")
		)
		(fp_line
			(start -0.508 -0.9398)
			(end -0.508 0.9398)
			(stroke
				(width 0.1524)
				(type default)
			)
			(layer "F.SilkS")
		)
		(fp_rect
			(start -0.508 0.9398)
			(end 0.508 -0.9398)
			(stroke
				(width 0)
				(type default)
			)
			(fill no)
			(layer "F.CrtYd")
		)
		(fp_rect
			(start -0.508 0.9398)
			(end 0.508 -0.9398)
			(stroke
				(width 0)
				(type default)
			)
			(fill no)
			(layer "F.Fab")
		)
		(pad "1" smd custom
			(at 0 -0.4445 90)
			(size 0.1397 0.1397)
			(layers "F.Cu" "F.Mask" "F.Paste")
			(net "P12V_B")
			(options
				(clearance outline)
				(anchor circle)
			)
			(primitives
				(gr_poly
					(pts
						(arc
							(start -0.1778 -0.2794)
							(mid -0.249642 -0.249642)
							(end -0.2794 -0.1778)
						)
						(arc
							(start -0.2794 0.1778)
							(mid -0.249642 0.249642)
							(end -0.1778 0.2794)
						)
						(arc
							(start 0.1778 0.2794)
							(mid 0.249642 0.249642)
							(end 0.2794 0.1778)
						)
						(arc
							(start 0.2794 -0.1778)
							(mid 0.249642 -0.249642)
							(end 0.1778 -0.2794)
						)
					)
					(width 0)
					(fill yes)
				)
			)
		)
		(pad "2" smd custom
			(at 0 0.4445 90)
			(size 0.1397 0.1397)
			(layers "F.Cu" "F.Mask" "F.Paste")
			(net "SW_HDD_P11")
			(options
				(clearance outline)
				(anchor circle)
			)
			(primitives
				(gr_poly
					(pts
						(arc
							(start -0.1778 -0.2794)
							(mid -0.249642 -0.249642)
							(end -0.2794 -0.1778)
						)
						(arc
							(start -0.2794 0.1778)
							(mid -0.249642 0.249642)
							(end -0.1778 0.2794)
						)
						(arc
							(start 0.1778 0.2794)
							(mid 0.249642 0.249642)
							(end 0.2794 0.1778)
						)
						(arc
							(start 0.2794 -0.1778)
							(mid 0.249642 -0.249642)
							(end 0.1778 -0.2794)
						)
					)
					(width 0)
					(fill yes)
				)
			)
		)
	)
	(footprint ""
		(layer "F.Cu")
		(at 220.6752 -196.723 90)
		(property "Reference" "C6"
			(at 0 0 90)
			(layer "F.SilkS")
			(hide yes)
			(effects
				(font
					(size 1.27 1.27)
				)
			)
		)
		(property "Value" "SCD1U16V2KX-3GP"
			(at 1.1811 -2.7051 90)
			(unlocked yes)
			(layer "F.Fab")
			(hide yes)
			(effects
				(font
					(size 1.016 1.016)
					(thickness 0.1524)
				)
			)
		)
		(property "Device Type" "C402H22"
			(at 1.1811 -4.2291 90)
			(unlocked yes)
			(layer "F.Fab")
			(hide yes)
			(effects
				(font
					(size 1.016 1.016)
					(thickness 0.1524)
				)
			)
		)
		(duplicate_pad_numbers_are_jumpers no)
		(fp_rect
			(start -0.4318 0.9525)
			(end 0.4318 -0.9525)
			(stroke
				(width 0)
				(type default)
			)
			(fill no)
			(layer "F.CrtYd")
		)
		(fp_rect
			(start -0.4318 0.9525)
			(end 0.4318 -0.9525)
			(stroke
				(width 0)
				(type default)
			)
			(fill no)
			(layer "F.Fab")
		)
		(pad "1" smd custom
			(at 0 -0.4445 90)
			(size 0.1524 0.1524)
			(layers "F.Cu" "F.Mask" "F.Paste")
			(net "P3V3_STBY_B")
			(options
				(clearance outline)
				(anchor circle)
			)
			(primitives
				(gr_poly
					(pts
						(arc
							(start 0.3048 -0.2032)
							(mid 0.275042 -0.275042)
							(end 0.2032 -0.3048)
						)
						(arc
							(start -0.2032 -0.3048)
							(mid -0.275042 -0.275042)
							(end -0.3048 -0.2032)
						)
						(arc
							(start -0.3048 0.2032)
							(mid -0.275042 0.275042)
							(end -0.2032 0.3048)
						)
						(arc
							(start 0.2032 0.3048)
							(mid 0.275042 0.275042)
							(end 0.3048 0.2032)
						)
					)
					(width 0)
					(fill yes)
				)
			)
		)
		(pad "2" smd custom
			(at 0 0.4445 90)
			(size 0.1524 0.1524)
			(layers "F.Cu" "F.Mask" "F.Paste")
			(net "GND")
			(options
				(clearance outline)
				(anchor circle)
			)
			(primitives
				(gr_poly
					(pts
						(arc
							(start 0.3048 -0.2032)
							(mid 0.275042 -0.275042)
							(end 0.2032 -0.3048)
						)
						(arc
							(start -0.2032 -0.3048)
							(mid -0.275042 -0.275042)
							(end -0.3048 -0.2032)
						)
						(arc
							(start -0.3048 0.2032)
							(mid -0.275042 0.275042)
							(end -0.2032 0.3048)
						)
						(arc
							(start 0.2032 0.3048)
							(mid 0.275042 0.275042)
							(end 0.3048 0.2032)
						)
					)
					(width 0)
					(fill yes)
				)
			)
		)
	)
	(footprint ""
		(layer "F.Cu")
		(at 172.974 -361.696)
		(property "Reference" "R1006"
			(at 0 0 0)
			(layer "F.SilkS")
			(hide yes)
			(effects
				(font
					(size 1.27 1.27)
				)
			)
		)
		(property "Value" "86K6R2F-2-GP"
			(at 0.064008 -3.993896 0)
			(unlocked yes)
			(layer "F.Fab")
			(hide yes)
			(effects
				(font
					(size 1.016 1.016)
					(thickness 0.1524)
				)
			)
		)
		(property "Device Type" "R402H16"
			(at 0.064008 -5.517896 0)
			(unlocked yes)
			(layer "F.Fab")
			(hide yes)
			(effects
				(font
					(size 1.016 1.016)
					(thickness 0.1524)
				)
			)
		)
		(duplicate_pad_numbers_are_jumpers no)
		(fp_line
			(start -0.508 -0.9398)
			(end -0.508 0.9398)
			(stroke
				(width 0.1524)
				(type default)
			)
			(layer "F.SilkS")
		)
		(fp_line
			(start 0.508 -0.9398)
			(end -0.508 -0.9398)
			(stroke
				(width 0.1524)
				(type default)
			)
			(layer "F.SilkS")
		)
		(fp_rect
			(start -0.508 0.9398)
			(end 0.508 -0.9398)
			(stroke
				(width 0)
				(type default)
			)
			(fill no)
			(layer "F.CrtYd")
		)
		(fp_rect
			(start -0.508 0.9398)
			(end 0.508 -0.9398)
			(stroke
				(width 0)
				(type default)
			)
			(fill no)
			(layer "F.Fab")
		)
		(pad "1" smd custom
			(at 0 -0.4445)
			(size 0.1397 0.1397)
			(layers "F.Cu" "F.Mask" "F.Paste")
			(net "MB0_ISET_R")
			(options
				(clearance outline)
				(anchor circle)
			)
			(primitives
				(gr_poly
					(pts
						(arc
							(start -0.1778 -0.2794)
							(mid -0.249642 -0.249642)
							(end -0.2794 -0.1778)
						)
						(arc
							(start -0.2794 0.1778)
							(mid -0.249642 0.249642)
							(end -0.1778 0.2794)
						)
						(arc
							(start 0.1778 0.2794)
							(mid 0.249642 0.249642)
							(end 0.2794 0.1778)
						)
						(arc
							(start 0.2794 -0.1778)
							(mid 0.249642 -0.249642)
							(end 0.1778 -0.2794)
						)
					)
					(width 0)
					(fill yes)
				)
			)
		)
		(pad "2" smd custom
			(at 0 0.4445)
			(size 0.1397 0.1397)
			(layers "F.Cu" "F.Mask" "F.Paste")
			(net "AGND_CURRENT_MON")
			(options
				(clearance outline)
				(anchor circle)
			)
			(primitives
				(gr_poly
					(pts
						(arc
							(start -0.1778 -0.2794)
							(mid -0.249642 -0.249642)
							(end -0.2794 -0.1778)
						)
						(arc
							(start -0.2794 0.1778)
							(mid -0.249642 0.249642)
							(end -0.1778 0.2794)
						)
						(arc
							(start 0.1778 0.2794)
							(mid 0.249642 0.249642)
							(end 0.2794 0.1778)
						)
						(arc
							(start 0.2794 -0.1778)
							(mid 0.249642 -0.249642)
							(end 0.1778 -0.2794)
						)
					)
					(width 0)
					(fill yes)
				)
			)
		)
	)
)
